(kicad_pcb
	(version 20260206)
	(generator "pcbnew")
	(generator_version "10.0")
	(general
		(thickness 1.6)
		(legacy_teardrops no)
	)
	(paper "A4")
	(title_block
		(title "timecard-production-celestica-r4006 — R4006-B0001-02_R01.brd")
		(comment 1 "Time Appliance Project (Time Card) / footprints 278-283 of 1113")
	)
	(layers
		(0 "F.Cu" signal "TOP")
		(4 "In1.Cu" signal "L02_GND1")
		(6 "In2.Cu" signal "L03_SIG1")
		(8 "In3.Cu" signal "L04_GND2")
		(10 "In4.Cu" signal "L05_VCC1")
		(12 "In5.Cu" signal "L06_VCC2")
		(14 "In6.Cu" signal "L07_GND3")
		(16 "In7.Cu" signal "L08_SIG2")
		(18 "In8.Cu" signal "L09_GND4")
		(2 "B.Cu" signal "BOTTOM")
		(9 "F.Adhes" user "F.Adhesive")
		(11 "B.Adhes" user "B.Adhesive")
		(13 "F.Paste" user "Package Geometry/Pastemask Top")
		(15 "B.Paste" user "Package Geometry/Pastemask Bottom")
		(5 "F.SilkS" user "Ref Des/Silkscreen Top")
		(7 "B.SilkS" user "Ref Des/Silkscreen Bottom")
		(1 "F.Mask" user "Board Geometry/Soldermask Top")
		(3 "B.Mask" user "Board Geometry/Soldermask Bottom")
		(17 "Dwgs.User" user "User.Drawings")
		(19 "Cmts.User" user "User.Comments")
		(21 "Eco1.User" user "User.Eco1")
		(23 "Eco2.User" user "User.Eco2")
		(25 "Edge.Cuts" user "Board Geometry/Outline")
		(27 "Margin" user)
		(31 "F.CrtYd" user "Package Geometry/Place Bound Top")
		(29 "B.CrtYd" user "Package Geometry/Place Bound Bottom")
		(35 "F.Fab" user "Ref Des/Assembly Top")
		(33 "B.Fab" user "Ref Des/Assembly Bottom")
	)
	(footprint ""
		(layer "F.Cu")
		(at 7.1374 -39.318692 90)
		(property "Reference" "R272"
			(at 2.337308 0.08255 90)
			(unlocked yes)
			(layer "F.SilkS")
			(effects
				(font
					(size 0.635 0.4064)
					(thickness 0.1524)
				)
			)
		)
		(property "Value" "VAL*"
			(at 0.02032 2.13233 90)
			(unlocked yes)
			(layer "F.Fab")
			(hide yes)
			(effects
				(font
					(size 0.7874 0.5842)
					(thickness 0.1524)
				)
			)
		)
		(property "Device Type" "RESISTOR-G155-11000-01,100OHM,A"
			(at 0.008382 1.210564 90)
			(unlocked yes)
			(layer "F.Fab")
			(hide yes)
			(effects
				(font
					(size 0.7874 0.5842)
					(thickness 0.1524)
				)
			)
		)
		(property "User Part Number" "PARTNUM*"
			(at 0.02032 4.024884 90)
			(unlocked yes)
			(layer "Cmts.User")
			(hide yes)
			(effects
				(font
					(size 0.7874 0.5842)
					(thickness 0.1524)
				)
			)
		)
		(property "Tolerance" "TOL*"
			(at 0.044704 3.05435 90)
			(unlocked yes)
			(layer "Cmts.User")
			(hide yes)
			(effects
				(font
					(size 0.7874 0.5842)
					(thickness 0.1524)
				)
			)
		)
		(duplicate_pad_numbers_are_jumpers no)
		(fp_line
			(start 1.143 -0.5588)
			(end -1.143 -0.5588)
			(stroke
				(width 0.1)
				(type default)
			)
			(layer "F.SilkS")
		)
		(fp_line
			(start -1.143 -0.5588)
			(end -1.143 0.5588)
			(stroke
				(width 0.1)
				(type default)
			)
			(layer "F.SilkS")
		)
		(fp_line
			(start 1.143 0.5588)
			(end 1.143 -0.5588)
			(stroke
				(width 0.1)
				(type default)
			)
			(layer "F.SilkS")
		)
		(fp_line
			(start -1.143 0.5588)
			(end 1.143 0.5588)
			(stroke
				(width 0.1)
				(type default)
			)
			(layer "F.SilkS")
		)
		(fp_poly
			(pts
				(xy -1.143 0.5588) (xy 1.143 0.5588) (xy 1.143 -0.5588) (xy -1.143 -0.5588)
			)
			(stroke
				(width 0)
				(type default)
			)
			(fill no)
			(layer "F.CrtYd")
		)
		(fp_line
			(start 0.508 -0.3048)
			(end -0.508 -0.3048)
			(stroke
				(width 0.1)
				(type default)
			)
			(layer "F.Fab")
		)
		(fp_line
			(start -0.508 -0.3048)
			(end -0.508 0.3048)
			(stroke
				(width 0.1)
				(type default)
			)
			(layer "F.Fab")
		)
		(fp_line
			(start 0.508 0.3048)
			(end 0.508 -0.3048)
			(stroke
				(width 0.1)
				(type default)
			)
			(layer "F.Fab")
		)
		(fp_line
			(start -0.508 0.3048)
			(end 0.508 0.3048)
			(stroke
				(width 0.1)
				(type default)
			)
			(layer "F.Fab")
		)
		(pad "1" smd rect
			(at -0.5334 0 90)
			(size 0.7112 0.6096)
			(layers "F.Cu" "F.Mask" "F.Paste")
			(net "FPGA_OUT_SMA1_LED_RED_N")
		)
		(pad "2" smd rect
			(at 0.5334 0 90)
			(size 0.7112 0.6096)
			(layers "F.Cu" "F.Mask" "F.Paste")
			(net "UNNAMED_14_LED4PV14_I265_3")
		)
		(zone
			(layer "F.Cu")
			(hatch none 0.5)
			(connect_pads
				(clearance 0)
			)
			(min_thickness 0.25)
			(keepout
				(tracks allowed)
				(vias not_allowed)
				(pads allowed)
				(copperpour not_allowed)
				(footprints allowed)
			)
			(placement
				(enabled no)
				(sheetname "")
			)
			(fill
				(thermal_gap 0.5)
				(thermal_bridge_width 0.5)
				(island_removal_mode 0)
			)
			(polygon
				(pts
					(xy 7.4422 -39.242492) (xy 7.4422 -39.394892) (xy 6.8326 -39.394892) (xy 6.8326 -39.242492)
				)
			)
		)
		(zone
			(layer "F.Cu")
			(hatch none 0.5)
			(connect_pads
				(clearance 0)
			)
			(min_thickness 0.25)
			(keepout
				(tracks not_allowed)
				(vias allowed)
				(pads allowed)
				(copperpour not_allowed)
				(footprints allowed)
			)
			(placement
				(enabled no)
				(sheetname "")
			)
			(fill
				(thermal_gap 0.5)
				(thermal_bridge_width 0.5)
				(island_removal_mode 0)
			)
			(polygon
				(pts
					(xy 7.4422 -39.242492) (xy 7.4422 -39.394892) (xy 6.8326 -39.394892) (xy 6.8326 -39.242492)
				)
			)
		)
	)
	(footprint ""
		(layer "F.Cu")
		(at 100.076 -56.769)
		(property "Reference" "TP186"
			(at 2.06375 0.4318 90)
			(unlocked yes)
			(layer "F.SilkS")
			(effects
				(font
					(size 0.635 0.4064)
					(thickness 0.1524)
				)
				(justify left)
			)
		)
		(property "Value" ""
			(at 0 0 0)
			(layer "F.Fab")
			(effects
				(font
					(size 1.27 1.27)
				)
			)
		)
		(property "Device Type" "TP_PIONT-TP010CT020B030_PTH-TPA"
			(at -1.341882 0.996696 0)
			(unlocked yes)
			(layer "F.Fab")
			(hide yes)
			(effects
				(font
					(size 0.7874 0.5842)
					(thickness 0.1524)
				)
				(justify left)
			)
		)
		(duplicate_pad_numbers_are_jumpers no)
		(fp_poly
			(pts
				(arc
					(start 0.889 0)
					(mid -0.889 0)
					(end 0.889 0)
				)
			)
			(stroke
				(width 0)
				(type default)
			)
			(fill no)
			(layer "B.CrtYd")
		)
		(fp_poly
			(pts
				(arc
					(start 0.889 0)
					(mid -0.889 0)
					(end 0.889 0)
				)
			)
			(stroke
				(width 0)
				(type default)
			)
			(fill no)
			(layer "F.CrtYd")
		)
		(pad "1" thru_hole circle
			(at 0 0)
			(size 0.508 0.508)
			(drill 0.254)
			(layers "*.Cu" "*.Mask")
			(remove_unused_layers no)
			(net "IO_L23N_16")
			(clearance 0.1016)
			(padstack
				(mode front_inner_back)
				(layer "Inner"
					(shape circle)
					(size 0.508 0.508)
					(clearance 0.1016)
				)
				(layer "B.Cu"
					(shape circle)
					(size 0.762 0.762)
					(clearance -0.0254)
				)
			)
		)
	)
	(footprint ""
		(layer "F.Cu")
		(at 99.5426 -64.2874 -90)
		(property "Reference" "R172"
			(at 2.6924 -0.69977 90)
			(unlocked yes)
			(layer "F.SilkS")
			(effects
				(font
					(size 0.7874 0.5842)
					(thickness 0.1524)
				)
			)
		)
		(property "Value" "VAL*"
			(at 0.02032 2.13233 270)
			(unlocked yes)
			(layer "F.Fab")
			(hide yes)
			(effects
				(font
					(size 0.7874 0.5842)
					(thickness 0.1524)
				)
			)
		)
		(property "Tolerance" "TOL*"
			(at 0.044704 3.05435 270)
			(unlocked yes)
			(layer "Cmts.User")
			(hide yes)
			(effects
				(font
					(size 0.7874 0.5842)
					(thickness 0.1524)
				)
			)
		)
		(property "User Part Number" "PARTNUM*"
			(at 0.02032 4.024884 270)
			(unlocked yes)
			(layer "Cmts.User")
			(hide yes)
			(effects
				(font
					(size 0.7874 0.5842)
					(thickness 0.1524)
				)
			)
		)
		(property "Device Type" "RESISTOR-G155-11002-01,10KOHM,A"
			(at 0.008382 1.210564 270)
			(unlocked yes)
			(layer "F.Fab")
			(hide yes)
			(effects
				(font
					(size 0.7874 0.5842)
					(thickness 0.1524)
				)
			)
		)
		(duplicate_pad_numbers_are_jumpers no)
		(fp_line
			(start -1.143 0.5588)
			(end 1.143 0.5588)
			(stroke
				(width 0.1)
				(type default)
			)
			(layer "F.SilkS")
		)
		(fp_line
			(start 1.143 0.5588)
			(end 1.143 -0.5588)
			(stroke
				(width 0.1)
				(type default)
			)
			(layer "F.SilkS")
		)
		(fp_line
			(start -1.143 -0.5588)
			(end -1.143 0.5588)
			(stroke
				(width 0.1)
				(type default)
			)
			(layer "F.SilkS")
		)
		(fp_line
			(start 1.143 -0.5588)
			(end -1.143 -0.5588)
			(stroke
				(width 0.1)
				(type default)
			)
			(layer "F.SilkS")
		)
		(fp_rect
			(start 1.143 0.5588)
			(end -1.143 -0.5588)
			(stroke
				(width 0)
				(type default)
			)
			(fill no)
			(layer "F.CrtYd")
		)
		(fp_line
			(start -0.508 0.3048)
			(end 0.508 0.3048)
			(stroke
				(width 0.1)
				(type default)
			)
			(layer "F.Fab")
		)
		(fp_line
			(start 0.508 0.3048)
			(end 0.508 -0.3048)
			(stroke
				(width 0.1)
				(type default)
			)
			(layer "F.Fab")
		)
		(fp_line
			(start -0.508 -0.3048)
			(end -0.508 0.3048)
			(stroke
				(width 0.1)
				(type default)
			)
			(layer "F.Fab")
		)
		(fp_line
			(start 0.508 -0.3048)
			(end -0.508 -0.3048)
			(stroke
				(width 0.1)
				(type default)
			)
			(layer "F.Fab")
		)
		(pad "1" smd rect
			(at -0.5334 0 270)
			(size 0.7112 0.6096)
			(layers "F.Cu" "F.Mask" "F.Paste")
			(net "XP3R3V_FPGA")
		)
		(pad "2" smd rect
			(at 0.5334 0 270)
			(size 0.7112 0.6096)
			(layers "F.Cu" "F.Mask" "F.Paste")
			(net "FPGA_IO_1")
		)
		(zone
			(layer "F.Cu")
			(hatch none 0.5)
			(connect_pads
				(clearance 0)
			)
			(min_thickness 0.25)
			(keepout
				(tracks allowed)
				(vias not_allowed)
				(pads allowed)
				(copperpour not_allowed)
				(footprints allowed)
			)
			(placement
				(enabled no)
				(sheetname "")
			)
			(fill
				(thermal_gap 0.5)
				(thermal_bridge_width 0.5)
				(island_removal_mode 0)
			)
			(polygon
				(pts
					(xy 99.2378 -64.2112) (xy 99.8474 -64.2112) (xy 99.8474 -64.3636) (xy 99.2378 -64.3636)
				)
			)
		)
	)
	(footprint ""
		(layer "F.Cu")
		(at 15.494 -83.566)
		(property "Reference" "R445"
			(at -1.397 1.18237 0)
			(unlocked yes)
			(layer "F.SilkS")
			(effects
				(font
					(size 0.7874 0.5842)
					(thickness 0.1524)
				)
			)
		)
		(property "Value" "VAL*"
			(at 0.02032 2.13233 0)
			(unlocked yes)
			(layer "F.Fab")
			(hide yes)
			(effects
				(font
					(size 0.7874 0.5842)
					(thickness 0.1524)
				)
			)
		)
		(property "Tolerance" "TOL*"
			(at 0.044704 3.05435 0)
			(unlocked yes)
			(layer "Cmts.User")
			(hide yes)
			(effects
				(font
					(size 0.7874 0.5842)
					(thickness 0.1524)
				)
			)
		)
		(property "User Part Number" "PARTNUM*"
			(at 0.02032 4.024884 0)
			(unlocked yes)
			(layer "Cmts.User")
			(hide yes)
			(effects
				(font
					(size 0.7874 0.5842)
					(thickness 0.1524)
				)
			)
		)
		(property "Device Type" "RESISTOR-G155-05101-01,5.1KOHMA"
			(at 0.008382 1.210564 0)
			(unlocked yes)
			(layer "F.Fab")
			(hide yes)
			(effects
				(font
					(size 0.7874 0.5842)
					(thickness 0.1524)
				)
			)
		)
		(duplicate_pad_numbers_are_jumpers no)
		(fp_line
			(start -1.143 -0.5588)
			(end -1.143 0.5588)
			(stroke
				(width 0.1)
				(type default)
			)
			(layer "F.SilkS")
		)
		(fp_line
			(start -1.143 0.5588)
			(end 1.143 0.5588)
			(stroke
				(width 0.1)
				(type default)
			)
			(layer "F.SilkS")
		)
		(fp_line
			(start 1.143 -0.5588)
			(end -1.143 -0.5588)
			(stroke
				(width 0.1)
				(type default)
			)
			(layer "F.SilkS")
		)
		(fp_line
			(start 1.143 0.5588)
			(end 1.143 -0.5588)
			(stroke
				(width 0.1)
				(type default)
			)
			(layer "F.SilkS")
		)
		(fp_poly
			(pts
				(xy -1.143 0.5588) (xy 1.143 0.5588) (xy 1.143 -0.5588) (xy -1.143 -0.5588)
			)
			(stroke
				(width 0)
				(type default)
			)
			(fill no)
			(layer "F.CrtYd")
		)
		(fp_line
			(start -0.508 -0.3048)
			(end -0.508 0.3048)
			(stroke
				(width 0.1)
				(type default)
			)
			(layer "F.Fab")
		)
		(fp_line
			(start -0.508 0.3048)
			(end 0.508 0.3048)
			(stroke
				(width 0.1)
				(type default)
			)
			(layer "F.Fab")
		)
		(fp_line
			(start 0.508 -0.3048)
			(end -0.508 -0.3048)
			(stroke
				(width 0.1)
				(type default)
			)
			(layer "F.Fab")
		)
		(fp_line
			(start 0.508 0.3048)
			(end 0.508 -0.3048)
			(stroke
				(width 0.1)
				(type default)
			)
			(layer "F.Fab")
		)
		(pad "1" smd rect
			(at -0.5334 0)
			(size 0.7112 0.6096)
			(layers "F.Cu" "F.Mask" "F.Paste")
			(net "UNNAMED_524_CONNUSB14PGH4FRAT_1")
		)
		(pad "2" smd rect
			(at 0.5334 0)
			(size 0.7112 0.6096)
			(layers "F.Cu" "F.Mask" "F.Paste")
			(net "SG")
		)
		(zone
			(layer "F.Cu")
			(hatch none 0.5)
			(connect_pads
				(clearance 0)
			)
			(min_thickness 0.25)
			(keepout
				(tracks not_allowed)
				(vias allowed)
				(pads allowed)
				(copperpour not_allowed)
				(footprints allowed)
			)
			(placement
				(enabled no)
				(sheetname "")
			)
			(fill
				(thermal_gap 0.5)
				(thermal_bridge_width 0.5)
				(island_removal_mode 0)
			)
			(polygon
				(pts
					(xy 15.4178 -83.2612) (xy 15.5702 -83.2612) (xy 15.5702 -83.8708) (xy 15.4178 -83.8708)
				)
			)
		)
		(zone
			(layer "F.Cu")
			(hatch none 0.5)
			(connect_pads
				(clearance 0)
			)
			(min_thickness 0.25)
			(keepout
				(tracks allowed)
				(vias not_allowed)
				(pads allowed)
				(copperpour not_allowed)
				(footprints allowed)
			)
			(placement
				(enabled no)
				(sheetname "")
			)
			(fill
				(thermal_gap 0.5)
				(thermal_bridge_width 0.5)
				(island_removal_mode 0)
			)
			(polygon
				(pts
					(xy 15.4178 -83.2612) (xy 15.5702 -83.2612) (xy 15.5702 -83.8708) (xy 15.4178 -83.8708)
				)
			)
		)
	)
	(footprint ""
		(layer "F.Cu")
		(at 103.632 -24.638)
		(property "Reference" "R242"
			(at -10.033 0.16637 0)
			(unlocked yes)
			(layer "F.SilkS")
			(effects
				(font
					(size 0.7874 0.5842)
					(thickness 0.1524)
				)
			)
		)
		(property "Value" "VAL*"
			(at 0.02032 2.13233 0)
			(unlocked yes)
			(layer "F.Fab")
			(hide yes)
			(effects
				(font
					(size 0.7874 0.5842)
					(thickness 0.1524)
				)
			)
		)
		(property "Tolerance" "TOL*"
			(at 0.044704 3.05435 0)
			(unlocked yes)
			(layer "Cmts.User")
			(hide yes)
			(effects
				(font
					(size 0.7874 0.5842)
					(thickness 0.1524)
				)
			)
		)
		(property "User Part Number" "PARTNUM*"
			(at 0.02032 4.024884 0)
			(unlocked yes)
			(layer "Cmts.User")
			(hide yes)
			(effects
				(font
					(size 0.7874 0.5842)
					(thickness 0.1524)
				)
			)
		)
		(property "Device Type" "RESISTOR-G155-11500-01,150OHM,A"
			(at 0.008382 1.210564 0)
			(unlocked yes)
			(layer "F.Fab")
			(hide yes)
			(effects
				(font
					(size 0.7874 0.5842)
					(thickness 0.1524)
				)
			)
		)
		(duplicate_pad_numbers_are_jumpers no)
		(fp_line
			(start -1.143 -0.5588)
			(end -1.143 0.5588)
			(stroke
				(width 0.1)
				(type default)
			)
			(layer "F.SilkS")
		)
		(fp_line
			(start -1.143 0.5588)
			(end 1.143 0.5588)
			(stroke
				(width 0.1)
				(type default)
			)
			(layer "F.SilkS")
		)
		(fp_line
			(start 1.143 -0.5588)
			(end -1.143 -0.5588)
			(stroke
				(width 0.1)
				(type default)
			)
			(layer "F.SilkS")
		)
		(fp_line
			(start 1.143 0.5588)
			(end 1.143 -0.5588)
			(stroke
				(width 0.1)
				(type default)
			)
			(layer "F.SilkS")
		)
		(fp_rect
			(start -1.143 0.5588)
			(end 1.143 -0.5588)
			(stroke
				(width 0)
				(type default)
			)
			(fill no)
			(layer "F.CrtYd")
		)
		(fp_line
			(start -0.508 -0.3048)
			(end -0.508 0.3048)
			(stroke
				(width 0.1)
				(type default)
			)
			(layer "F.Fab")
		)
		(fp_line
			(start -0.508 0.3048)
			(end 0.508 0.3048)
			(stroke
				(width 0.1)
				(type default)
			)
			(layer "F.Fab")
		)
		(fp_line
			(start 0.508 -0.3048)
			(end -0.508 -0.3048)
			(stroke
				(width 0.1)
				(type default)
			)
			(layer "F.Fab")
		)
		(fp_line
			(start 0.508 0.3048)
			(end 0.508 -0.3048)
			(stroke
				(width 0.1)
				(type default)
			)
			(layer "F.Fab")
		)
		(pad "1" smd rect
			(at -0.5334 0)
			(size 0.7112 0.6096)
			(layers "F.Cu" "F.Mask" "F.Paste")
			(net "OSC_125M_CLKP")
		)
		(pad "2" smd rect
			(at 0.5334 0)
			(size 0.7112 0.6096)
			(layers "F.Cu" "F.Mask" "F.Paste")
			(net "SG")
		)
		(zone
			(layer "F.Cu")
			(hatch none 0.5)
			(connect_pads
				(clearance 0)
			)
			(min_thickness 0.25)
			(keepout
				(tracks allowed)
				(vias not_allowed)
				(pads allowed)
				(copperpour not_allowed)
				(footprints allowed)
			)
			(placement
				(enabled no)
				(sheetname "")
			)
			(fill
				(thermal_gap 0.5)
				(thermal_bridge_width 0.5)
				(island_removal_mode 0)
			)
			(polygon
				(pts
					(xy 103.5558 -24.3332) (xy 103.7082 -24.3332) (xy 103.7082 -24.9428) (xy 103.5558 -24.9428)
				)
			)
		)
	)
	(footprint ""
		(layer "F.Cu")
		(at 31.115 -96.266)
		(property "Reference" "C87"
			(at 3.08737 1.016 90)
			(unlocked yes)
			(layer "F.SilkS")
			(effects
				(font
					(size 0.7874 0.5842)
					(thickness 0.1524)
				)
			)
		)
		(property "Value" "VAL*"
			(at 0.193548 2.13614 0)
			(unlocked yes)
			(layer "F.Fab")
			(hide yes)
			(effects
				(font
					(size 0.7874 0.5842)
					(thickness 0.1524)
				)
			)
		)
		(property "Tolerance" "TOL*"
			(at 0.216154 3.1496 0)
			(unlocked yes)
			(layer "Cmts.User")
			(hide yes)
			(effects
				(font
					(size 0.7874 0.5842)
					(thickness 0.1524)
				)
			)
		)
		(property "Device Type" "CAPACITOR-G104-0A180-FJ,18PF,5%"
			(at 0.184404 1.180592 0)
			(unlocked yes)
			(layer "F.Fab")
			(hide yes)
			(effects
				(font
					(size 0.7874 0.5842)
					(thickness 0.1524)
				)
			)
		)
		(property "User Part Number" "PARTNUM*"
			(at 0.216154 4.185666 0)
			(unlocked yes)
			(layer "Cmts.User")
			(hide yes)
			(effects
				(font
					(size 0.7874 0.5842)
					(thickness 0.1524)
				)
			)
		)
		(duplicate_pad_numbers_are_jumpers no)
		(fp_line
			(start -0.671322 -0.4445)
			(end 0.671322 -0.4445)
			(stroke
				(width 0.1)
				(type default)
			)
			(layer "F.SilkS")
		)
		(fp_line
			(start -0.671322 0.4445)
			(end -0.671322 -0.4445)
			(stroke
				(width 0.1)
				(type default)
			)
			(layer "F.SilkS")
		)
		(fp_line
			(start 0.671322 -0.4445)
			(end 0.671322 0.4445)
			(stroke
				(width 0.1)
				(type default)
			)
			(layer "F.SilkS")
		)
		(fp_line
			(start 0.671322 0.4445)
			(end -0.671322 0.4445)
			(stroke
				(width 0.1)
				(type default)
			)
			(layer "F.SilkS")
		)
		(fp_rect
			(start -0.671322 -0.4445)
			(end 0.671322 0.4445)
			(stroke
				(width 0)
				(type default)
			)
			(fill no)
			(layer "F.CrtYd")
		)
		(fp_line
			(start -0.31496 -0.1651)
			(end -0.31496 0.1651)
			(stroke
				(width 0.1)
				(type default)
			)
			(layer "F.Fab")
		)
		(fp_line
			(start -0.31496 0.1651)
			(end 0.31496 0.1651)
			(stroke
				(width 0.1)
				(type default)
			)
			(layer "F.Fab")
		)
		(fp_line
			(start 0.31496 -0.1651)
			(end -0.31496 -0.1651)
			(stroke
				(width 0.1)
				(type default)
			)
			(layer "F.Fab")
		)
		(fp_line
			(start 0.31496 0.1651)
			(end 0.31496 -0.1651)
			(stroke
				(width 0.1)
				(type default)
			)
			(layer "F.Fab")
		)
		(pad "1" smd rect
			(at -0.264922 0)
			(size 0.3048 0.381)
			(layers "F.Cu" "F.Mask" "F.Paste")
			(net "SG")
		)
		(pad "2" smd rect
			(at 0.264922 0)
			(size 0.3048 0.381)
			(layers "F.Cu" "F.Mask" "F.Paste")
			(net "UNNAMED_524_CAPACITOR_I10_2")
		)
		(zone
			(layer "F.Cu")
			(hatch none 0.5)
			(connect_pads
				(clearance 0)
			)
			(min_thickness 0.25)
			(keepout
				(tracks allowed)
				(vias not_allowed)
				(pads allowed)
				(copperpour not_allowed)
				(footprints allowed)
			)
			(placement
				(enabled no)
				(sheetname "")
			)
			(fill
				(thermal_gap 0.5)
				(thermal_bridge_width 0.5)
				(island_removal_mode 0)
			)
			(polygon
				(pts
					(xy 31.002478 -96.4565) (xy 31.002478 -96.0755) (xy 31.227522 -96.0755) (xy 31.227522 -96.4565)
				)
			)
		)
	)
)
